# T6G (Grand Teton) — schematic netlist excerpt (pin names and nets, part order shuffled) for the footprints in the layout excerpt that follows; sources: Cadence DE-HDL packaged netlist, KiCad conversion of 04192023_DAF0TMB3IC0_F0TG_MB_C_brd_V02_OCP.brd

R4163  Q_RES  100K 1% EMPTY  pkg 0402LF  page 124 : A = GPU_3V3IO_RSVD3 ; B = GND
R513  Q_RES  2.2K 5% CHIP  pkg 0402LF  page 54 : A = P3V3_AUX ; B = CPU1_SP5R4

(kicad_pcb
	(version 20260206)
	(generator "pcbnew")
	(generator_version "10.0")
	(general
		(thickness 1.6)
		(legacy_teardrops no)
	)
	(paper "A4")
	(title_block
		(title "04192023_DAF0TMB3IC0_F0TG_MB_C_brd_V02_OCP.brd")
		(comment 1 "Grand Teton / footprints 6382-6383 of 8354")
	)
	(layers
		(0 "F.Cu" signal "TOP")
		(4 "In1.Cu" signal "GND")
		(6 "In2.Cu" signal "IN1")
		(8 "In3.Cu" signal "GND1")
		(10 "In4.Cu" signal "IN2")
		(12 "In5.Cu" signal "GND2")
		(14 "In6.Cu" signal "IN3")
		(16 "In7.Cu" signal "GND3")
		(18 "In8.Cu" signal "VCC")
		(20 "In9.Cu" signal "VCC1")
		(22 "In10.Cu" signal "GND4")
		(24 "In11.Cu" signal "IN4")
		(26 "In12.Cu" signal "GND5")
		(28 "In13.Cu" signal "IN5")
		(30 "In14.Cu" signal "GND6")
		(32 "In15.Cu" signal "IN6")
		(34 "In16.Cu" signal "GND7")
		(2 "B.Cu" signal "BOTTOM")
		(9 "F.Adhes" user "F.Adhesive")
		(11 "B.Adhes" user "B.Adhesive")
		(13 "F.Paste" user "Package Geometry/Pastemask Top")
		(15 "B.Paste" user "Package Geometry/Pastemask Bottom")
		(5 "F.SilkS" user "Ref Des/Silkscreen Top")
		(7 "B.SilkS" user "Ref Des/Silkscreen Bottom")
		(1 "F.Mask" user "Board Geometry/Soldermask Top")
		(3 "B.Mask" user "Board Geometry/Soldermask Bottom")
		(17 "Dwgs.User" user "User.Drawings")
		(19 "Cmts.User" user "User.Comments")
		(21 "Eco1.User" user "User.Eco1")
		(23 "Eco2.User" user "User.Eco2")
		(25 "Edge.Cuts" user "Board Geometry/Outline")
		(27 "Margin" user)
		(31 "F.CrtYd" user "Package Geometry/Place Bound Top")
		(29 "B.CrtYd" user "Package Geometry/Place Bound Bottom")
		(35 "F.Fab" user "Ref Des/Assembly Top")
		(33 "B.Fab" user "Ref Des/Assembly Bottom")
	)
	(footprint ""
		(layer "B.Cu")
		(at 156.151834 -320.798952)
		(property "Reference" "R513"
			(at 0 0 0)
			(layer "B.SilkS")
			(hide yes)
			(effects
				(font
					(size 1.27 1.27)
				)
				(justify mirror)
			)
		)
		(property "Value" ""
			(at 0 0 0)
			(layer "B.Fab")
			(effects
				(font
					(size 1.27 1.27)
				)
				(justify mirror)
			)
		)
		(duplicate_pad_numbers_are_jumpers no)
		(fp_line
			(start -0.7874 -0.4064)
			(end -0.7874 0.4064)
			(stroke
				(width 0.1524)
				(type default)
			)
			(layer "B.SilkS")
		)
		(fp_line
			(start -0.7874 0.4064)
			(end 0.7874 0.4064)
			(stroke
				(width 0.1524)
				(type default)
			)
			(layer "B.SilkS")
		)
		(fp_line
			(start 0.7874 -0.4064)
			(end -0.7874 -0.4064)
			(stroke
				(width 0.1524)
				(type default)
			)
			(layer "B.SilkS")
		)
		(fp_line
			(start 0.7874 0.4064)
			(end 0.7874 -0.4064)
			(stroke
				(width 0.1524)
				(type default)
			)
			(layer "B.SilkS")
		)
		(fp_line
			(start -0.67945 -0.3048)
			(end -0.67945 0.3048)
			(stroke
				(width 0.1)
				(type default)
			)
			(layer "B.Fab")
		)
		(fp_line
			(start -0.67945 0.3048)
			(end -0.120396 0.3048)
			(stroke
				(width 0.1)
				(type default)
			)
			(layer "B.Fab")
		)
		(fp_line
			(start -0.12065 -0.3048)
			(end -0.67945 -0.3048)
			(stroke
				(width 0.1)
				(type default)
			)
			(layer "B.Fab")
		)
		(fp_line
			(start -0.12065 -0.2794)
			(end -0.12065 -0.3048)
			(stroke
				(width 0.1)
				(type default)
			)
			(layer "B.Fab")
		)
		(fp_line
			(start -0.120396 0.2794)
			(end 0.12065 0.2794)
			(stroke
				(width 0.1)
				(type default)
			)
			(layer "B.Fab")
		)
		(fp_line
			(start -0.120396 0.3048)
			(end -0.120396 0.2794)
			(stroke
				(width 0.1)
				(type default)
			)
			(layer "B.Fab")
		)
		(fp_line
			(start 0.12065 -0.305054)
			(end 0.12065 -0.2794)
			(stroke
				(width 0.1)
				(type default)
			)
			(layer "B.Fab")
		)
		(fp_line
			(start 0.12065 -0.2794)
			(end -0.12065 -0.2794)
			(stroke
				(width 0.1)
				(type default)
			)
			(layer "B.Fab")
		)
		(fp_line
			(start 0.12065 0.2794)
			(end 0.12065 0.3048)
			(stroke
				(width 0.1)
				(type default)
			)
			(layer "B.Fab")
		)
		(fp_line
			(start 0.12065 0.3048)
			(end 0.67945 0.3048)
			(stroke
				(width 0.1)
				(type default)
			)
			(layer "B.Fab")
		)
		(fp_line
			(start 0.67945 -0.305054)
			(end 0.12065 -0.305054)
			(stroke
				(width 0.1)
				(type default)
			)
			(layer "B.Fab")
		)
		(fp_line
			(start 0.67945 0.3048)
			(end 0.67945 -0.305054)
			(stroke
				(width 0.1)
				(type default)
			)
			(layer "B.Fab")
		)
		(pad "1" smd circle
			(at 0.40005 0 180)
			(size 0 0)
			(layers "B.Cu" "B.Mask" "B.Paste")
			(net "P3V3_AUX")
		)
		(pad "2" smd circle
			(at -0.40005 0 180)
			(size 0 0)
			(layers "B.Cu" "B.Mask" "B.Paste")
			(net "CPU1_SP5R4")
		)
	)
	(footprint ""
		(layer "B.Cu")
		(at 428.087282 -436.414672 90)
		(property "Reference" "R4163"
			(at 0 0 90)
			(layer "B.SilkS")
			(hide yes)
			(effects
				(font
					(size 1.27 1.27)
				)
				(justify mirror)
			)
		)
		(property "Value" ""
			(at 0 0 90)
			(layer "B.Fab")
			(effects
				(font
					(size 1.27 1.27)
				)
				(justify mirror)
			)
		)
		(duplicate_pad_numbers_are_jumpers no)
		(fp_line
			(start 0.7874 -0.4064)
			(end -0.7874 -0.4064)
			(stroke
				(width 0.1524)
				(type default)
			)
			(layer "B.SilkS")
		)
		(fp_line
			(start -0.7874 -0.4064)
			(end -0.7874 0.4064)
			(stroke
				(width 0.1524)
				(type default)
			)
			(layer "B.SilkS")
		)
		(fp_line
			(start 0.7874 0.4064)
			(end 0.7874 -0.4064)
			(stroke
				(width 0.1524)
				(type default)
			)
			(layer "B.SilkS")
		)
		(fp_line
			(start -0.7874 0.4064)
			(end 0.7874 0.4064)
			(stroke
				(width 0.1524)
				(type default)
			)
			(layer "B.SilkS")
		)
		(fp_line
			(start 0.67945 -0.305054)
			(end 0.12065 -0.305054)
			(stroke
				(width 0.1)
				(type default)
			)
			(layer "B.Fab")
		)
		(fp_line
			(start 0.12065 -0.305054)
			(end 0.12065 -0.2794)
			(stroke
				(width 0.1)
				(type default)
			)
			(layer "B.Fab")
		)
		(fp_line
			(start -0.12065 -0.3048)
			(end -0.67945 -0.3048)
			(stroke
				(width 0.1)
				(type default)
			)
			(layer "B.Fab")
		)
		(fp_line
			(start -0.67945 -0.3048)
			(end -0.67945 0.3048)
			(stroke
				(width 0.1)
				(type default)
			)
			(layer "B.Fab")
		)
		(fp_line
			(start 0.12065 -0.2794)
			(end -0.12065 -0.2794)
			(stroke
				(width 0.1)
				(type default)
			)
			(layer "B.Fab")
		)
		(fp_line
			(start -0.12065 -0.2794)
			(end -0.12065 -0.3048)
			(stroke
				(width 0.1)
				(type default)
			)
			(layer "B.Fab")
		)
		(fp_line
			(start 0.12065 0.2794)
			(end 0.12065 0.3048)
			(stroke
				(width 0.1)
				(type default)
			)
			(layer "B.Fab")
		)
		(fp_line
			(start -0.120396 0.2794)
			(end 0.12065 0.2794)
			(stroke
				(width 0.1)
				(type default)
			)
			(layer "B.Fab")
		)
		(fp_line
			(start 0.67945 0.3048)
			(end 0.67945 -0.305054)
			(stroke
				(width 0.1)
				(type default)
			)
			(layer "B.Fab")
		)
		(fp_line
			(start 0.12065 0.3048)
			(end 0.67945 0.3048)
			(stroke
				(width 0.1)
				(type default)
			)
			(layer "B.Fab")
		)
		(fp_line
			(start -0.120396 0.3048)
			(end -0.120396 0.2794)
			(stroke
				(width 0.1)
				(type default)
			)
			(layer "B.Fab")
		)
		(fp_line
			(start -0.67945 0.3048)
			(end -0.120396 0.3048)
			(stroke
				(width 0.1)
				(type default)
			)
			(layer "B.Fab")
		)
		(pad "1" smd circle
			(at 0.40005 0 270)
			(size 0 0)
			(layers "B.Cu" "B.Mask" "B.Paste")
			(net "GPU_3V3IO_RSVD3")
		)
		(pad "2" smd circle
			(at -0.40005 0 270)
			(size 0 0)
			(layers "B.Cu" "B.Mask" "B.Paste")
			(net "GND")
		)
	)
)
